(kicad_pcb
	(version 20260206)
	(generator "pcbnew")
	(generator_version "10.0")
	(general
		(thickness 1.6)
		(legacy_teardrops no)
	)
	(paper "A4")
	(title_block
		(title "dpb — 14545-sa.0730WZS0815.brd")
		(comment 1 "Honey Badger (Wiwynn) / footprints 504-506 of 1066")
	)
	(layers
		(0 "F.Cu" signal "TOP")
		(4 "In1.Cu" signal "L2GND")
		(6 "In2.Cu" signal "L3")
		(8 "In3.Cu" signal "L4VCC")
		(10 "In4.Cu" signal "L5VCC")
		(12 "In5.Cu" signal "L6")
		(14 "In6.Cu" signal "L7GND")
		(2 "B.Cu" signal "BOTTOM")
		(9 "F.Adhes" user "F.Adhesive")
		(11 "B.Adhes" user "B.Adhesive")
		(13 "F.Paste" user "Package Geometry/Pastemask Top")
		(15 "B.Paste" user "Package Geometry/Pastemask Bottom")
		(5 "F.SilkS" user "Ref Des/Silkscreen Top")
		(7 "B.SilkS" user "Ref Des/Silkscreen Bottom")
		(1 "F.Mask" user "Board Geometry/Soldermask Top")
		(3 "B.Mask" user "Board Geometry/Soldermask Bottom")
		(17 "Dwgs.User" user "User.Drawings")
		(19 "Cmts.User" user "User.Comments")
		(21 "Eco1.User" user "User.Eco1")
		(23 "Eco2.User" user "User.Eco2")
		(25 "Edge.Cuts" user "Board Geometry/Outline")
		(27 "Margin" user)
		(31 "F.CrtYd" user "Package Geometry/Place Bound Top")
		(29 "B.CrtYd" user "Package Geometry/Place Bound Bottom")
		(35 "F.Fab" user "Ref Des/Assembly Top")
		(33 "B.Fab" user "Ref Des/Assembly Bottom")
	)
	(footprint ""
		(layer "F.Cu")
		(at 42.500042 -273.670014 90)
		(property "Reference" "SKT8"
			(at 0 0 90)
			(layer "F.SilkS")
			(hide yes)
			(effects
				(font
					(size 1.27 1.27)
				)
			)
		)
		(property "Value" "SKT-SATA14P-15P-12-GP"
			(at -22.6187 8.1788 90)
			(unlocked yes)
			(layer "F.Fab")
			(hide yes)
			(effects
				(font
					(size 1.016 1.016)
					(thickness 0.1524)
				)
			)
		)
		(property "Device Type" "87945-1001"
			(at -22.6187 6.6548 90)
			(unlocked yes)
			(layer "F.Fab")
			(hide yes)
			(effects
				(font
					(size 1.016 1.016)
					(thickness 0.1524)
				)
			)
		)
		(duplicate_pad_numbers_are_jumpers no)
		(fp_line
			(start -15.3924 -5.8547)
			(end -16.3576 -5.8547)
			(stroke
				(width 0.3302)
				(type default)
			)
			(layer "F.SilkS")
		)
		(fp_line
			(start 20.4724 -5.7658)
			(end 20.4724 -2.3114)
			(stroke
				(width 0.1524)
				(type default)
			)
			(layer "F.SilkS")
		)
		(fp_line
			(start -20.4724 -5.7658)
			(end 20.4724 -5.7658)
			(stroke
				(width 0.1524)
				(type default)
			)
			(layer "F.SilkS")
		)
		(fp_line
			(start 23.7617 -2.3114)
			(end 23.7617 2.3114)
			(stroke
				(width 0.1524)
				(type default)
			)
			(layer "F.SilkS")
		)
		(fp_line
			(start 20.4724 -2.3114)
			(end 23.7617 -2.3114)
			(stroke
				(width 0.1524)
				(type default)
			)
			(layer "F.SilkS")
		)
		(fp_line
			(start -20.4724 -2.3114)
			(end -20.4724 -5.7658)
			(stroke
				(width 0.1524)
				(type default)
			)
			(layer "F.SilkS")
		)
		(fp_line
			(start -23.7617 -2.3114)
			(end -20.4724 -2.3114)
			(stroke
				(width 0.1524)
				(type default)
			)
			(layer "F.SilkS")
		)
		(fp_line
			(start 23.117556 -0.5461)
			(end 23.117556 0.5461)
			(stroke
				(width 0.3048)
				(type default)
			)
			(layer "F.SilkS")
		)
		(fp_line
			(start -20.882356 -0.5461)
			(end -20.882356 0.5461)
			(stroke
				(width 0.3048)
				(type default)
			)
			(layer "F.SilkS")
		)
		(fp_line
			(start 20.882356 0.5461)
			(end 20.882356 -0.5461)
			(stroke
				(width 0.3048)
				(type default)
			)
			(layer "F.SilkS")
		)
		(fp_line
			(start -23.117556 0.5461)
			(end -23.117556 -0.5461)
			(stroke
				(width 0.3048)
				(type default)
			)
			(layer "F.SilkS")
		)
		(fp_line
			(start 23.7617 2.3114)
			(end 20.4724 2.3114)
			(stroke
				(width 0.1524)
				(type default)
			)
			(layer "F.SilkS")
		)
		(fp_line
			(start 20.4724 2.3114)
			(end 20.4724 9.652)
			(stroke
				(width 0.1524)
				(type default)
			)
			(layer "F.SilkS")
		)
		(fp_line
			(start -20.4724 2.3114)
			(end -23.7617 2.3114)
			(stroke
				(width 0.1524)
				(type default)
			)
			(layer "F.SilkS")
		)
		(fp_line
			(start -23.7617 2.3114)
			(end -23.7617 -2.3114)
			(stroke
				(width 0.1524)
				(type default)
			)
			(layer "F.SilkS")
		)
		(fp_line
			(start 17.8435 7.9502)
			(end -17.8435 7.9502)
			(stroke
				(width 0.1524)
				(type default)
			)
			(layer "F.SilkS")
		)
		(fp_line
			(start -17.8435 7.9502)
			(end -17.8435 9.652)
			(stroke
				(width 0.1524)
				(type default)
			)
			(layer "F.SilkS")
		)
		(fp_line
			(start 20.4724 9.652)
			(end 17.8435 9.652)
			(stroke
				(width 0.1524)
				(type default)
			)
			(layer "F.SilkS")
		)
		(fp_line
			(start 17.8435 9.652)
			(end 17.8435 7.9502)
			(stroke
				(width 0.1524)
				(type default)
			)
			(layer "F.SilkS")
		)
		(fp_line
			(start -17.8435 9.652)
			(end -20.4724 9.652)
			(stroke
				(width 0.1524)
				(type default)
			)
			(layer "F.SilkS")
		)
		(fp_line
			(start -20.4724 9.652)
			(end -20.4724 2.3114)
			(stroke
				(width 0.1524)
				(type default)
			)
			(layer "F.SilkS")
		)
		(fp_arc
			(start 20.882356 -0.5461)
			(mid 21.999956 -1.6637)
			(end 23.117556 -0.5461)
			(stroke
				(width 0.3048)
				(type default)
			)
			(layer "F.SilkS")
		)
		(fp_arc
			(start -23.117556 -0.5461)
			(mid -21.999956 -1.6637)
			(end -20.882356 -0.5461)
			(stroke
				(width 0.3048)
				(type default)
			)
			(layer "F.SilkS")
		)
		(fp_arc
			(start 23.117556 0.5461)
			(mid 21.999956 1.6637)
			(end 20.882356 0.5461)
			(stroke
				(width 0.3048)
				(type default)
			)
			(layer "F.SilkS")
		)
		(fp_arc
			(start -20.882356 0.5461)
			(mid -21.999956 1.6637)
			(end -23.117556 0.5461)
			(stroke
				(width 0.3048)
				(type default)
			)
			(layer "F.SilkS")
		)
		(fp_poly
			(pts
				(xy -15.87119 -5.838698) (xy -15.23619 -6.473698) (xy -16.50619 -6.473698)
			)
			(stroke
				(width 0)
				(type default)
			)
			(fill yes)
			(layer "F.SilkS")
		)
		(fp_poly
			(pts
				(xy -20.2184 -5.5118) (xy 20.2184 -5.5118) (xy 20.2184 -2.0574) (xy 23.5077 -2.0574) (xy 23.5077 2.0574)
				(xy 20.2184 2.0574) (xy 20.2184 9.398) (xy 18.0975 9.398) (xy 18.0975 7.6962) (xy -18.0975 7.6962)
				(xy -18.0975 9.398) (xy -20.2184 9.398) (xy -20.2184 2.0574) (xy -23.5077 2.0574) (xy -23.5077 -2.0574)
				(xy -20.2184 -2.0574)
			)
			(stroke
				(width 0)
				(type default)
			)
			(fill no)
			(layer "F.CrtYd")
		)
		(fp_poly
			(pts
				(xy -20.2184 -5.5118) (xy -20.2184 -6.0198) (xy -20.7264 -6.0198) (xy -20.7264 -2.5654) (xy -24.0157 -2.5654)
				(xy -24.0157 2.5654) (xy -20.7264 2.5654) (xy -20.7264 9.906) (xy -17.5895 9.906) (xy -17.5895 8.2042)
				(xy 17.5895 8.2042) (xy 17.5895 9.906) (xy 20.7264 9.906) (xy 20.7264 2.5654) (xy 24.0157 2.5654)
				(xy 24.0157 -2.5654) (xy 20.7264 -2.5654) (xy 20.7264 -6.0198) (xy -20.21586 -6.0198) (xy -20.21586 -5.5118)
				(xy 20.2184 -5.5118) (xy 20.2184 -2.0574) (xy 23.5077 -2.0574) (xy 23.5077 2.0574) (xy 20.2184 2.0574)
				(xy 20.2184 9.398) (xy 18.0975 9.398) (xy 18.0975 7.6962) (xy -18.0975 7.6962) (xy -18.0975 9.398)
				(xy -20.2184 9.398) (xy -20.2184 2.0574) (xy -23.5077 2.0574) (xy -23.5077 -2.0574) (xy -20.2184 -2.0574)
			)
			(stroke
				(width 0)
				(type default)
			)
			(fill no)
			(layer "F.CrtYd")
		)
		(fp_poly
			(pts
				(xy -20.7264 -6.0198) (xy -20.7264 -2.5654) (xy -24.0157 -2.5654) (xy -24.0157 2.5654) (xy -20.7264 2.5654)
				(xy -20.7264 9.906) (xy -17.5895 9.906) (xy -17.5895 8.2042) (xy 17.5895 8.2042) (xy 17.5895 9.906)
				(xy 20.7264 9.906) (xy 20.7264 2.5654) (xy 24.0157 2.5654) (xy 24.0157 -2.5654) (xy 20.7264 -2.5654)
				(xy 20.7264 -6.0198)
			)
			(stroke
				(width 0)
				(type default)
			)
			(fill no)
			(layer "F.Fab")
		)
		(pad "" np_thru_hole circle
			(at -18.999962 -2.350008 90)
			(size 0.254 0.254)
			(drill 1.8542)
			(layers "*.Cu" "*.Mask")
			(clearance 1.1557)
			(thermal_gap 1.1557)
		)
		(pad "" np_thru_hole circle
			(at 18.999962 -2.350008 90)
			(size 0.254 0.254)
			(drill 1.8542)
			(layers "*.Cu" "*.Mask")
			(clearance 1.1557)
			(thermal_gap 1.1557)
		)
		(pad "H1" thru_hole oval
			(at -21.999956 0 90)
			(size 1.524 2.6162)
			(drill oval 0.8128 1.905)
			(layers "*.Cu" "*.Mask")
			(remove_unused_layers no)
			(net "GND")
			(clearance 0.1524)
			(thermal_gap 0.1524)
		)
		(pad "H2" thru_hole oval
			(at 21.999956 0 90)
			(size 1.524 2.6162)
			(drill oval 0.8128 1.905)
			(layers "*.Cu" "*.Mask")
			(remove_unused_layers no)
			(net "GND")
			(clearance 0.1524)
			(thermal_gap 0.1524)
		)
		(pad "P1" smd rect
			(at -1.89992 -4.249928 90)
			(size 0.6604 2.3876)
			(layers "F.Cu" "F.Mask" "F.Paste")
			(net "Net_10")
		)
		(pad "P2" smd rect
			(at -0.62992 -4.249928 90)
			(size 0.6604 2.3876)
			(layers "F.Cu" "F.Mask" "F.Paste")
			(net "Net_9")
		)
		(pad "P3" smd rect
			(at 0.64008 -4.249928 90)
			(size 0.6604 2.3876)
			(layers "F.Cu" "F.Mask" "F.Paste")
			(net "Net_8")
		)
		(pad "P4" smd rect
			(at 1.91008 -4.249928 90)
			(size 0.6604 2.3876)
			(layers "F.Cu" "F.Mask" "F.Paste")
			(net "GND")
		)
		(pad "P5" smd rect
			(at 3.18008 -4.249928 90)
			(size 0.6604 2.3876)
			(layers "F.Cu" "F.Mask" "F.Paste")
			(net "HDD_PRSNT_NET7")
		)
		(pad "P6" smd rect
			(at 4.45008 -4.249928 90)
			(size 0.6604 2.3876)
			(layers "F.Cu" "F.Mask" "F.Paste")
			(net "GND")
		)
		(pad "P7" smd rect
			(at 5.72008 -4.249928 90)
			(size 0.6604 2.3876)
			(layers "F.Cu" "F.Mask" "F.Paste")
			(net "5V_PRE_7")
		)
		(pad "P8" smd rect
			(at 6.99008 -4.249928 90)
			(size 0.6604 2.3876)
			(layers "F.Cu" "F.Mask" "F.Paste")
			(net "P5V_HDD7")
		)
		(pad "P9" smd rect
			(at 8.26008 -4.249928 90)
			(size 0.6604 2.3876)
			(layers "F.Cu" "F.Mask" "F.Paste")
			(net "P5V_HDD7")
		)
		(pad "P10" smd rect
			(at 9.53008 -4.249928 90)
			(size 0.6604 2.3876)
			(layers "F.Cu" "F.Mask" "F.Paste")
			(net "GND")
		)
		(pad "P11" smd rect
			(at 10.80008 -4.249928 90)
			(size 0.6604 2.3876)
			(layers "F.Cu" "F.Mask" "F.Paste")
			(net "ACT_HDD7")
		)
		(pad "P12" smd rect
			(at 12.07008 -4.249928 90)
			(size 0.6604 2.3876)
			(layers "F.Cu" "F.Mask" "F.Paste")
			(net "GND")
		)
		(pad "P13" smd rect
			(at 13.34008 -4.249928 90)
			(size 0.6604 2.3876)
			(layers "F.Cu" "F.Mask" "F.Paste")
			(net "12V_PRE_7")
		)
		(pad "P14" smd rect
			(at 14.61008 -4.249928 90)
			(size 0.6604 2.3876)
			(layers "F.Cu" "F.Mask" "F.Paste")
			(net "P12V_HDD7")
		)
		(pad "P15" smd rect
			(at 15.88008 -4.249928 90)
			(size 0.6604 2.3876)
			(layers "F.Cu" "F.Mask" "F.Paste")
			(net "P12V_HDD7")
		)
		(pad "S1" smd rect
			(at -15.86992 -4.249928 90)
			(size 0.6604 2.3876)
			(layers "F.Cu" "F.Mask" "F.Paste")
			(net "GND")
		)
		(pad "S2" smd rect
			(at -14.59992 -4.249928 90)
			(size 0.6604 2.3876)
			(layers "F.Cu" "F.Mask" "F.Paste")
			(net "SAS2X28_A_HDD7_TX_+")
		)
		(pad "S3" smd rect
			(at -13.32992 -4.249928 90)
			(size 0.6604 2.3876)
			(layers "F.Cu" "F.Mask" "F.Paste")
			(net "SAS2X28_A_HDD7_TX_-")
		)
		(pad "S4" smd rect
			(at -12.05992 -4.249928 90)
			(size 0.6604 2.3876)
			(layers "F.Cu" "F.Mask" "F.Paste")
			(net "GND")
		)
		(pad "S5" smd rect
			(at -10.78992 -4.249928 90)
			(size 0.6604 2.3876)
			(layers "F.Cu" "F.Mask" "F.Paste")
			(net "SAS2X28_DRIVE_RX_N_A7")
		)
		(pad "S6" smd rect
			(at -9.51992 -4.249928 90)
			(size 0.6604 2.3876)
			(layers "F.Cu" "F.Mask" "F.Paste")
			(net "SAS2X28_DRIVE_RX_P_A7")
		)
		(pad "S7" smd rect
			(at -8.24992 -4.249928 90)
			(size 0.6604 2.3876)
			(layers "F.Cu" "F.Mask" "F.Paste")
			(net "GND")
		)
		(pad "S8" smd rect
			(at -7.480046 -2.100072 90)
			(size 0.508 1.905)
			(layers "F.Cu" "F.Mask" "F.Paste")
			(net "GND")
		)
		(pad "S9" smd rect
			(at -6.679946 -2.100072 90)
			(size 0.508 1.905)
			(layers "F.Cu" "F.Mask" "F.Paste")
			(net "SAS2X28_B_HDD7_TX_+")
		)
		(pad "S10" smd rect
			(at -5.8801 -2.100072 90)
			(size 0.508 1.905)
			(layers "F.Cu" "F.Mask" "F.Paste")
			(net "SAS2X28_B_HDD7_TX_-")
		)
		(pad "S11" smd rect
			(at -5.08 -2.100072 90)
			(size 0.508 1.905)
			(layers "F.Cu" "F.Mask" "F.Paste")
			(net "GND")
		)
		(pad "S12" smd rect
			(at -4.2799 -2.100072 90)
			(size 0.508 1.905)
			(layers "F.Cu" "F.Mask" "F.Paste")
			(net "SAS2X28_DRIVE_RX_N_B7")
		)
		(pad "S13" smd rect
			(at -3.480054 -2.100072 90)
			(size 0.508 1.905)
			(layers "F.Cu" "F.Mask" "F.Paste")
			(net "SAS2X28_DRIVE_RX_P_B7")
		)
		(pad "S14" smd rect
			(at -2.679954 -2.100072 90)
			(size 0.508 1.905)
			(layers "F.Cu" "F.Mask" "F.Paste")
			(net "GND")
		)
		(zone
			(layers "F.Cu" "B.Cu" "In1.Cu" "In2.Cu" "In3.Cu" "In4.Cu" "In5.Cu" "In6.Cu")
			(hatch none 0.5)
			(connect_pads
				(clearance 0)
			)
			(min_thickness 0.25)
			(keepout
				(tracks not_allowed)
				(vias allowed)
				(pads allowed)
				(copperpour not_allowed)
				(footprints allowed)
			)
			(placement
				(enabled no)
				(sheetname "")
			)
			(fill
				(thermal_gap 0.5)
				(thermal_bridge_width 0.5)
				(island_removal_mode 0)
			)
			(polygon
				(pts
					(arc
						(start 41.381934 -292.669976)
						(mid 38.918134 -292.669976)
						(end 41.381934 -292.669976)
					)
				)
			)
		)
		(zone
			(layers "F.Cu" "B.Cu" "In1.Cu" "In2.Cu" "In3.Cu" "In4.Cu" "In5.Cu" "In6.Cu")
			(hatch none 0.5)
			(connect_pads
				(clearance 0)
			)
			(min_thickness 0.25)
			(keepout
				(tracks not_allowed)
				(vias allowed)
				(pads allowed)
				(copperpour not_allowed)
				(footprints allowed)
			)
			(placement
				(enabled no)
				(sheetname "")
			)
			(fill
				(thermal_gap 0.5)
				(thermal_bridge_width 0.5)
				(island_removal_mode 0)
			)
			(polygon
				(pts
					(arc
						(start 41.381934 -254.670052)
						(mid 38.918134 -254.670052)
						(end 41.381934 -254.670052)
					)
				)
			)
		)
	)
	(footprint ""
		(layer "F.Cu")
		(at 230.335582 -247.495568 90)
		(property "Reference" "R128"
			(at 0 0 90)
			(layer "F.SilkS")
			(hide yes)
			(effects
				(font
					(size 1.27 1.27)
				)
			)
		)
		(property "Value" "10KR2F-2-GP"
			(at 0.064008 -3.993896 90)
			(unlocked yes)
			(layer "F.Fab")
			(hide yes)
			(effects
				(font
					(size 1.016 1.016)
					(thickness 0.1524)
				)
			)
		)
		(property "Device Type" "R402H16"
			(at 0.064008 -5.517896 90)
			(unlocked yes)
			(layer "F.Fab")
			(hide yes)
			(effects
				(font
					(size 1.016 1.016)
					(thickness 0.1524)
				)
			)
		)
		(duplicate_pad_numbers_are_jumpers no)
		(fp_line
			(start 0.508 -0.9398)
			(end -0.508 -0.9398)
			(stroke
				(width 0.1524)
				(type default)
			)
			(layer "F.SilkS")
		)
		(fp_line
			(start -0.508 -0.9398)
			(end -0.508 0.9398)
			(stroke
				(width 0.1524)
				(type default)
			)
			(layer "F.SilkS")
		)
		(fp_rect
			(start -0.508 0.9398)
			(end 0.508 -0.9398)
			(stroke
				(width 0)
				(type default)
			)
			(fill no)
			(layer "F.CrtYd")
		)
		(fp_rect
			(start -0.508 0.9398)
			(end 0.508 -0.9398)
			(stroke
				(width 0)
				(type default)
			)
			(fill no)
			(layer "F.Fab")
		)
		(pad "1" smd custom
			(at 0 -0.4445 90)
			(size 0.1397 0.1397)
			(layers "F.Cu" "F.Mask" "F.Paste")
			(net "P5VA")
			(options
				(clearance outline)
				(anchor circle)
			)
			(primitives
				(gr_poly
					(pts
						(arc
							(start -0.1778 -0.2794)
							(mid -0.249642 -0.249642)
							(end -0.2794 -0.1778)
						)
						(arc
							(start -0.2794 0.1778)
							(mid -0.249642 0.249642)
							(end -0.1778 0.2794)
						)
						(arc
							(start 0.1778 0.2794)
							(mid 0.249642 0.249642)
							(end 0.2794 0.1778)
						)
						(arc
							(start 0.2794 -0.1778)
							(mid 0.249642 -0.249642)
							(end 0.1778 -0.2794)
						)
					)
					(width 0)
					(fill yes)
				)
			)
		)
		(pad "2" smd custom
			(at 0 0.4445 90)
			(size 0.1397 0.1397)
			(layers "F.Cu" "F.Mask" "F.Paste")
			(net "DRIVE_ACT_2")
			(options
				(clearance outline)
				(anchor circle)
			)
			(primitives
				(gr_poly
					(pts
						(arc
							(start -0.1778 -0.2794)
							(mid -0.249642 -0.249642)
							(end -0.2794 -0.1778)
						)
						(arc
							(start -0.2794 0.1778)
							(mid -0.249642 0.249642)
							(end -0.1778 0.2794)
						)
						(arc
							(start 0.1778 0.2794)
							(mid 0.249642 0.249642)
							(end 0.2794 0.1778)
						)
						(arc
							(start 0.2794 -0.1778)
							(mid 0.249642 -0.249642)
							(end 0.1778 -0.2794)
						)
					)
					(width 0)
					(fill yes)
				)
			)
		)
	)
	(footprint ""
		(layer "F.Cu")
		(at 214.2998 -79.2988)
		(property "Reference" "TP29"
			(at 0 0 0)
			(layer "F.SilkS")
			(hide yes)
			(effects
				(font
					(size 1.27 1.27)
				)
			)
		)
		(property "Value" "TPAD32-GP"
			(at 0 -3.166364 0)
			(unlocked yes)
			(layer "F.Fab")
			(hide yes)
			(effects
				(font
					(size 1.016 1.016)
					(thickness 0.1524)
				)
			)
		)
		(property "Device Type" "TPAD32"
			(at 0 -4.690618 0)
			(unlocked yes)
			(layer "F.Fab")
			(hide yes)
			(effects
				(font
					(size 1.016 1.016)
					(thickness 0.1524)
				)
			)
		)
		(duplicate_pad_numbers_are_jumpers no)
		(fp_poly
			(pts
				(arc
					(start 0.4064 0)
					(mid -0.4064 0)
					(end 0.4064 0)
				)
			)
			(stroke
				(width 0)
				(type default)
			)
			(fill no)
			(layer "F.CrtYd")
		)
		(fp_poly
			(pts
				(arc
					(start 0.7112 0)
					(mid -0.7112 0)
					(end 0.7112 0)
				)
			)
			(stroke
				(width 0)
				(type default)
			)
			(fill no)
			(layer "F.Fab")
		)
		(pad "1" smd circle
			(at 0 0)
			(size 0.8128 0.8128)
			(layers "F.Cu" "F.Mask" "F.Paste")
			(net "ACT_HDD4")
		)
	)
)
